(kicad_pcb
	(version 20260206)
	(generator "pcbnew")
	(generator_version "10.0")
	(general
		(thickness 1.6)
		(legacy_teardrops no)
	)
	(paper "A4")
	(title_block
		(title "01162023_DA0F0TEBIF0_F0T_Expander_BD_F_brd_V02_OCP.brd")
		(comment 1 "Grand Teton / footprint 2022 of 9728 (J21), pads 1-109 of 179")
	)
	(layers
		(0 "F.Cu" signal "TOP")
		(4 "In1.Cu" signal "GND")
		(6 "In2.Cu" signal "VCC")
		(8 "In3.Cu" signal "VCC1")
		(10 "In4.Cu" signal "GND1")
		(12 "In5.Cu" signal "IN1")
		(14 "In6.Cu" signal "GND2")
		(16 "In7.Cu" signal "IN2")
		(18 "In8.Cu" signal "GND3")
		(20 "In9.Cu" signal "IN3")
		(22 "In10.Cu" signal "GND4")
		(24 "In11.Cu" signal "IN4")
		(26 "In12.Cu" signal "GND5")
		(28 "In13.Cu" signal "IN5")
		(30 "In14.Cu" signal "GND6")
		(32 "In15.Cu" signal "IN6")
		(34 "In16.Cu" signal "GND7")
		(2 "B.Cu" signal "BOTTOM")
		(9 "F.Adhes" user "F.Adhesive")
		(11 "B.Adhes" user "B.Adhesive")
		(13 "F.Paste" user "Package Geometry/Pastemask Top")
		(15 "B.Paste" user "Package Geometry/Pastemask Bottom")
		(5 "F.SilkS" user "Ref Des/Silkscreen Top")
		(7 "B.SilkS" user "Ref Des/Silkscreen Bottom")
		(1 "F.Mask" user "Board Geometry/Soldermask Top")
		(3 "B.Mask" user "Board Geometry/Soldermask Bottom")
		(17 "Dwgs.User" user "User.Drawings")
		(19 "Cmts.User" user "User.Comments")
		(21 "Eco1.User" user "User.Eco1")
		(23 "Eco2.User" user "User.Eco2")
		(25 "Edge.Cuts" user "Board Geometry/Outline")
		(27 "Margin" user)
		(31 "F.CrtYd" user "Package Geometry/Place Bound Top")
		(29 "B.CrtYd" user "Package Geometry/Place Bound Bottom")
		(35 "F.Fab" user "Ref Des/Assembly Top")
		(33 "B.Fab" user "Ref Des/Assembly Bottom")
	)
	(footprint ""
		(layer "F.Cu")
		(at 71.980044 -127.700024 180)
		(property "Reference" "J21"
			(at 5.278374 -34.786824 90)
			(unlocked yes)
			(layer "F.SilkS")
			(effects
				(font
					(size 0.7874 0.5842)
					(thickness 0.1524)
				)
				(justify left)
			)
		)
		(property "Value" ""
			(at 0 0 180)
			(layer "F.Fab")
			(effects
				(font
					(size 1.27 1.27)
				)
			)
		)
		(duplicate_pad_numbers_are_jumpers no)
		(pad "" np_thru_hole circle
			(at -0.727456 -32.485076 180)
			(size 1.1176 1.1176)
			(drill 1.1176)
			(layers "*.Cu" "*.Mask")
			(clearance 0.381)
			(thermal_gap 0.381)
		)
		(pad "" np_thru_hole circle
			(at 1.022604 32.485076 180)
			(size 1.1176 1.1176)
			(drill 1.1176)
			(layers "*.Cu" "*.Mask")
			(clearance 0.381)
			(thermal_gap 0.381)
		)
		(pad "A1" smd rect
			(at 3.322574 -18.465038 90)
			(size 0.3556 1.2192)
			(layers "F.Cu" "F.Mask" "F.Paste")
			(net "GND")
		)
		(pad "A2" smd rect
			(at 3.322574 -17.86509 90)
			(size 0.3556 1.2192)
			(layers "F.Cu" "F.Mask" "F.Paste")
			(net "GND")
		)
		(pad "A3" smd rect
			(at 3.322574 -17.264888 90)
			(size 0.3556 1.2192)
			(layers "F.Cu" "F.Mask" "F.Paste")
			(net "GND")
		)
		(pad "A4" smd rect
			(at 3.322574 -16.66494 90)
			(size 0.3556 1.2192)
			(layers "F.Cu" "F.Mask" "F.Paste")
			(net "GND")
		)
		(pad "A5" smd rect
			(at 3.322574 -16.064992 90)
			(size 0.3556 1.2192)
			(layers "F.Cu" "F.Mask" "F.Paste")
			(net "GND")
		)
		(pad "A6" smd rect
			(at 3.322574 -15.465044 90)
			(size 0.3556 1.2192)
			(layers "F.Cu" "F.Mask" "F.Paste")
			(net "GND")
		)
		(pad "A7" smd rect
			(at 3.322574 -14.865096 90)
			(size 0.3556 1.2192)
			(layers "F.Cu" "F.Mask" "F.Paste")
			(net "SMB_NIC1_R_SCL")
		)
		(pad "A8" smd rect
			(at 3.322574 -14.264894 90)
			(size 0.3556 1.2192)
			(layers "F.Cu" "F.Mask" "F.Paste")
			(net "SMB_NIC1_R_SDA")
		)
		(pad "A9" smd rect
			(at 3.322574 -13.664946 90)
			(size 0.3556 1.2192)
			(layers "F.Cu" "F.Mask" "F.Paste")
			(net "RST_SMB_NIC1_MUX_ISO_R_N")
		)
		(pad "A10" smd rect
			(at 3.322574 -13.064998 90)
			(size 0.3556 1.2192)
			(layers "F.Cu" "F.Mask" "F.Paste")
			(net "GND")
		)
		(pad "A11" smd rect
			(at 3.322574 -12.46505 90)
			(size 0.3556 1.2192)
			(layers "F.Cu" "F.Mask" "F.Paste")
			(net "RST_NIC1_PERST1_R_N")
		)
		(pad "A12" smd rect
			(at 3.322574 -11.865102 90)
			(size 0.3556 1.2192)
			(layers "F.Cu" "F.Mask" "F.Paste")
			(net "PRSNTB2_NIC1_N")
		)
		(pad "A13" smd rect
			(at 3.322574 -11.2649 90)
			(size 0.3556 1.2192)
			(layers "F.Cu" "F.Mask" "F.Paste")
			(net "GND")
		)
		(pad "A14" smd rect
			(at 3.322574 -10.664952 90)
			(size 0.3556 1.2192)
			(layers "F.Cu" "F.Mask" "F.Paste")
			(net "Net_2588")
		)
		(pad "A15" smd rect
			(at 3.322574 -10.065004 90)
			(size 0.3556 1.2192)
			(layers "F.Cu" "F.Mask" "F.Paste")
			(net "Net_2591")
		)
		(pad "A16" smd rect
			(at 3.322574 -9.465056 90)
			(size 0.3556 1.2192)
			(layers "F.Cu" "F.Mask" "F.Paste")
			(net "GND")
		)
		(pad "A17" smd rect
			(at 3.322574 -8.865108 90)
			(size 0.3556 1.2192)
			(layers "F.Cu" "F.Mask" "F.Paste")
			(net "P5E_PEX0_STN0_RX_DN<0>")
		)
		(pad "A18" smd rect
			(at 3.322574 -8.264906 90)
			(size 0.3556 1.2192)
			(layers "F.Cu" "F.Mask" "F.Paste")
			(net "P5E_PEX0_STN0_RX_DP<0>")
		)
		(pad "A19" smd rect
			(at 3.322574 -7.664958 90)
			(size 0.3556 1.2192)
			(layers "F.Cu" "F.Mask" "F.Paste")
			(net "GND")
		)
		(pad "A20" smd rect
			(at 3.322574 -7.06501 90)
			(size 0.3556 1.2192)
			(layers "F.Cu" "F.Mask" "F.Paste")
			(net "P5E_PEX0_STN0_RX_DN<1>")
		)
		(pad "A21" smd rect
			(at 3.322574 -6.465062 90)
			(size 0.3556 1.2192)
			(layers "F.Cu" "F.Mask" "F.Paste")
			(net "P5E_PEX0_STN0_RX_DP<1>")
		)
		(pad "A22" smd rect
			(at 3.322574 -5.865114 90)
			(size 0.3556 1.2192)
			(layers "F.Cu" "F.Mask" "F.Paste")
			(net "GND")
		)
		(pad "A23" smd rect
			(at 3.322574 -5.264912 90)
			(size 0.3556 1.2192)
			(layers "F.Cu" "F.Mask" "F.Paste")
			(net "P5E_PEX0_STN0_RX_DN<2>")
		)
		(pad "A24" smd rect
			(at 3.322574 -4.664964 90)
			(size 0.3556 1.2192)
			(layers "F.Cu" "F.Mask" "F.Paste")
			(net "P5E_PEX0_STN0_RX_DP<2>")
		)
		(pad "A25" smd rect
			(at 3.322574 -4.065016 90)
			(size 0.3556 1.2192)
			(layers "F.Cu" "F.Mask" "F.Paste")
			(net "GND")
		)
		(pad "A26" smd rect
			(at 3.322574 -3.465068 90)
			(size 0.3556 1.2192)
			(layers "F.Cu" "F.Mask" "F.Paste")
			(net "P5E_PEX0_STN0_RX_DN<3>")
		)
		(pad "A27" smd rect
			(at 3.322574 -2.86512 90)
			(size 0.3556 1.2192)
			(layers "F.Cu" "F.Mask" "F.Paste")
			(net "P5E_PEX0_STN0_RX_DP<3>")
		)
		(pad "A28" smd rect
			(at 3.322574 -2.264918 90)
			(size 0.3556 1.2192)
			(layers "F.Cu" "F.Mask" "F.Paste")
			(net "GND")
		)
		(pad "A29" smd rect
			(at 3.322574 1.74498 90)
			(size 0.3556 1.2192)
			(layers "F.Cu" "F.Mask" "F.Paste")
			(net "GND")
		)
		(pad "A30" smd rect
			(at 3.322574 2.344928 90)
			(size 0.3556 1.2192)
			(layers "F.Cu" "F.Mask" "F.Paste")
			(net "P5E_PEX0_STN0_RX_DN<4>")
		)
		(pad "A31" smd rect
			(at 3.322574 2.944876 90)
			(size 0.3556 1.2192)
			(layers "F.Cu" "F.Mask" "F.Paste")
			(net "P5E_PEX0_STN0_RX_DP<4>")
		)
		(pad "A32" smd rect
			(at 3.322574 3.545078 90)
			(size 0.3556 1.2192)
			(layers "F.Cu" "F.Mask" "F.Paste")
			(net "GND")
		)
		(pad "A33" smd rect
			(at 3.322574 4.145026 90)
			(size 0.3556 1.2192)
			(layers "F.Cu" "F.Mask" "F.Paste")
			(net "P5E_PEX0_STN0_RX_DN<5>")
		)
		(pad "A34" smd rect
			(at 3.322574 4.744974 90)
			(size 0.3556 1.2192)
			(layers "F.Cu" "F.Mask" "F.Paste")
			(net "P5E_PEX0_STN0_RX_DP<5>")
		)
		(pad "A35" smd rect
			(at 3.322574 5.344922 90)
			(size 0.3556 1.2192)
			(layers "F.Cu" "F.Mask" "F.Paste")
			(net "GND")
		)
		(pad "A36" smd rect
			(at 3.322574 5.945124 90)
			(size 0.3556 1.2192)
			(layers "F.Cu" "F.Mask" "F.Paste")
			(net "P5E_PEX0_STN0_RX_DN<6>")
		)
		(pad "A37" smd rect
			(at 3.322574 6.545072 90)
			(size 0.3556 1.2192)
			(layers "F.Cu" "F.Mask" "F.Paste")
			(net "P5E_PEX0_STN0_RX_DP<6>")
		)
		(pad "A38" smd rect
			(at 3.322574 7.14502 90)
			(size 0.3556 1.2192)
			(layers "F.Cu" "F.Mask" "F.Paste")
			(net "GND")
		)
		(pad "A39" smd rect
			(at 3.322574 7.744968 90)
			(size 0.3556 1.2192)
			(layers "F.Cu" "F.Mask" "F.Paste")
			(net "P5E_PEX0_STN0_RX_DN<7>")
		)
		(pad "A40" smd rect
			(at 3.322574 8.344916 90)
			(size 0.3556 1.2192)
			(layers "F.Cu" "F.Mask" "F.Paste")
			(net "P5E_PEX0_STN0_RX_DP<7>")
		)
		(pad "A41" smd rect
			(at 3.322574 8.945118 90)
			(size 0.3556 1.2192)
			(layers "F.Cu" "F.Mask" "F.Paste")
			(net "GND")
		)
		(pad "A42" smd rect
			(at 3.322574 9.545066 90)
			(size 0.3556 1.2192)
			(layers "F.Cu" "F.Mask" "F.Paste")
			(net "PRSNTB1_NIC1_N")
		)
		(pad "A43" smd rect
			(at 3.322574 14.454886 90)
			(size 0.3556 1.2192)
			(layers "F.Cu" "F.Mask" "F.Paste")
			(net "GND")
		)
		(pad "A44" smd rect
			(at 3.322574 15.055088 90)
			(size 0.3556 1.2192)
			(layers "F.Cu" "F.Mask" "F.Paste")
			(net "P5E_PEX0_STN0_RX_DN<8>")
		)
		(pad "A45" smd rect
			(at 3.322574 15.655036 90)
			(size 0.3556 1.2192)
			(layers "F.Cu" "F.Mask" "F.Paste")
			(net "P5E_PEX0_STN0_RX_DP<8>")
		)
		(pad "A46" smd rect
			(at 3.322574 16.254984 90)
			(size 0.3556 1.2192)
			(layers "F.Cu" "F.Mask" "F.Paste")
			(net "GND")
		)
		(pad "A47" smd rect
			(at 3.322574 16.854932 90)
			(size 0.3556 1.2192)
			(layers "F.Cu" "F.Mask" "F.Paste")
			(net "P5E_PEX0_STN0_RX_DN<9>")
		)
		(pad "A48" smd rect
			(at 3.322574 17.45488 90)
			(size 0.3556 1.2192)
			(layers "F.Cu" "F.Mask" "F.Paste")
			(net "P5E_PEX0_STN0_RX_DP<9>")
		)
		(pad "A49" smd rect
			(at 3.322574 18.055082 90)
			(size 0.3556 1.2192)
			(layers "F.Cu" "F.Mask" "F.Paste")
			(net "GND")
		)
		(pad "A50" smd rect
			(at 3.322574 18.65503 90)
			(size 0.3556 1.2192)
			(layers "F.Cu" "F.Mask" "F.Paste")
			(net "P5E_PEX0_STN0_RX_DN<10>")
		)
		(pad "A51" smd rect
			(at 3.322574 19.254978 90)
			(size 0.3556 1.2192)
			(layers "F.Cu" "F.Mask" "F.Paste")
			(net "P5E_PEX0_STN0_RX_DP<10>")
		)
		(pad "A52" smd rect
			(at 3.322574 19.854926 90)
			(size 0.3556 1.2192)
			(layers "F.Cu" "F.Mask" "F.Paste")
			(net "GND")
		)
		(pad "A53" smd rect
			(at 3.322574 20.455128 90)
			(size 0.3556 1.2192)
			(layers "F.Cu" "F.Mask" "F.Paste")
			(net "P5E_PEX0_STN0_RX_DN<11>")
		)
		(pad "A54" smd rect
			(at 3.322574 21.055076 90)
			(size 0.3556 1.2192)
			(layers "F.Cu" "F.Mask" "F.Paste")
			(net "P5E_PEX0_STN0_RX_DP<11>")
		)
		(pad "A55" smd rect
			(at 3.322574 21.655024 90)
			(size 0.3556 1.2192)
			(layers "F.Cu" "F.Mask" "F.Paste")
			(net "GND")
		)
		(pad "A56" smd rect
			(at 3.322574 22.254972 90)
			(size 0.3556 1.2192)
			(layers "F.Cu" "F.Mask" "F.Paste")
			(net "P5E_PEX0_STN0_RX_DN<12>")
		)
		(pad "A57" smd rect
			(at 3.322574 22.85492 90)
			(size 0.3556 1.2192)
			(layers "F.Cu" "F.Mask" "F.Paste")
			(net "P5E_PEX0_STN0_RX_DP<12>")
		)
		(pad "A58" smd rect
			(at 3.322574 23.455122 90)
			(size 0.3556 1.2192)
			(layers "F.Cu" "F.Mask" "F.Paste")
			(net "GND")
		)
		(pad "A59" smd rect
			(at 3.322574 24.05507 90)
			(size 0.3556 1.2192)
			(layers "F.Cu" "F.Mask" "F.Paste")
			(net "P5E_PEX0_STN0_RX_DN<13>")
		)
		(pad "A60" smd rect
			(at 3.322574 24.655018 90)
			(size 0.3556 1.2192)
			(layers "F.Cu" "F.Mask" "F.Paste")
			(net "P5E_PEX0_STN0_RX_DP<13>")
		)
		(pad "A61" smd rect
			(at 3.322574 25.254966 90)
			(size 0.3556 1.2192)
			(layers "F.Cu" "F.Mask" "F.Paste")
			(net "GND")
		)
		(pad "A62" smd rect
			(at 3.322574 25.854914 90)
			(size 0.3556 1.2192)
			(layers "F.Cu" "F.Mask" "F.Paste")
			(net "P5E_PEX0_STN0_RX_DN<14>")
		)
		(pad "A63" smd rect
			(at 3.322574 26.455116 90)
			(size 0.3556 1.2192)
			(layers "F.Cu" "F.Mask" "F.Paste")
			(net "P5E_PEX0_STN0_RX_DP<14>")
		)
		(pad "A64" smd rect
			(at 3.322574 27.055064 90)
			(size 0.3556 1.2192)
			(layers "F.Cu" "F.Mask" "F.Paste")
			(net "GND")
		)
		(pad "A65" smd rect
			(at 3.322574 27.655012 90)
			(size 0.3556 1.2192)
			(layers "F.Cu" "F.Mask" "F.Paste")
			(net "P5E_PEX0_STN0_RX_DN<15>")
		)
		(pad "A66" smd rect
			(at 3.322574 28.25496 90)
			(size 0.3556 1.2192)
			(layers "F.Cu" "F.Mask" "F.Paste")
			(net "P5E_PEX0_STN0_RX_DP<15>")
		)
		(pad "A67" smd rect
			(at 3.322574 28.854908 90)
			(size 0.3556 1.2192)
			(layers "F.Cu" "F.Mask" "F.Paste")
			(net "GND")
		)
		(pad "A68" smd rect
			(at 3.322574 29.45511 90)
			(size 0.3556 1.2192)
			(layers "F.Cu" "F.Mask" "F.Paste")
			(net "Net_2596")
		)
		(pad "A69" smd rect
			(at 3.322574 30.055058 90)
			(size 0.3556 1.2192)
			(layers "F.Cu" "F.Mask" "F.Paste")
			(net "Net_2597")
		)
		(pad "A70" smd rect
			(at 3.322574 30.655006 90)
			(size 0.3556 1.2192)
			(layers "F.Cu" "F.Mask" "F.Paste")
			(net "NIC1_PWRBRK_R_N")
		)
		(pad "B1" smd rect
			(at -1.27762 -18.465038 90)
			(size 0.3556 1.2192)
			(layers "F.Cu" "F.Mask" "F.Paste")
			(net "P12V_NIC1")
		)
		(pad "B2" smd rect
			(at -1.27762 -17.86509 90)
			(size 0.3556 1.2192)
			(layers "F.Cu" "F.Mask" "F.Paste")
			(net "P12V_NIC1")
		)
		(pad "B3" smd rect
			(at -1.27762 -17.264888 90)
			(size 0.3556 1.2192)
			(layers "F.Cu" "F.Mask" "F.Paste")
			(net "P12V_NIC1")
		)
		(pad "B4" smd rect
			(at -1.27762 -16.66494 90)
			(size 0.3556 1.2192)
			(layers "F.Cu" "F.Mask" "F.Paste")
			(net "P12V_NIC1")
		)
		(pad "B5" smd rect
			(at -1.27762 -16.064992 90)
			(size 0.3556 1.2192)
			(layers "F.Cu" "F.Mask" "F.Paste")
			(net "P12V_NIC1")
		)
		(pad "B6" smd rect
			(at -1.27762 -15.465044 90)
			(size 0.3556 1.2192)
			(layers "F.Cu" "F.Mask" "F.Paste")
			(net "P12V_NIC1")
		)
		(pad "B7" smd rect
			(at -1.27762 -14.865096 90)
			(size 0.3556 1.2192)
			(layers "F.Cu" "F.Mask" "F.Paste")
			(net "NIC1_BIF0_N")
		)
		(pad "B8" smd rect
			(at -1.27762 -14.264894 90)
			(size 0.3556 1.2192)
			(layers "F.Cu" "F.Mask" "F.Paste")
			(net "NIC1_BIF1_N")
		)
		(pad "B9" smd rect
			(at -1.27762 -13.664946 90)
			(size 0.3556 1.2192)
			(layers "F.Cu" "F.Mask" "F.Paste")
			(net "NIC1_BIF2_N")
		)
		(pad "B10" smd rect
			(at -1.27762 -13.064998 90)
			(size 0.3556 1.2192)
			(layers "F.Cu" "F.Mask" "F.Paste")
			(net "RST_NIC1_PERST0_R_N")
		)
		(pad "B11" smd rect
			(at -1.27762 -12.46505 90)
			(size 0.3556 1.2192)
			(layers "F.Cu" "F.Mask" "F.Paste")
			(net "P3V3_NIC1")
		)
		(pad "B12" smd rect
			(at -1.27762 -11.865102 90)
			(size 0.3556 1.2192)
			(layers "F.Cu" "F.Mask" "F.Paste")
			(net "NIC1_AUX_PWR_EN_R")
		)
		(pad "B13" smd rect
			(at -1.27762 -11.2649 90)
			(size 0.3556 1.2192)
			(layers "F.Cu" "F.Mask" "F.Paste")
			(net "GND")
		)
		(pad "B14" smd rect
			(at -1.27762 -10.664952 90)
			(size 0.3556 1.2192)
			(layers "F.Cu" "F.Mask" "F.Paste")
			(net "CLK_100M_DB2000QL_NIC1_R_DN")
		)
		(pad "B15" smd rect
			(at -1.27762 -10.065004 90)
			(size 0.3556 1.2192)
			(layers "F.Cu" "F.Mask" "F.Paste")
			(net "CLK_100M_DB2000QL_NIC1_R_DP")
		)
		(pad "B16" smd rect
			(at -1.27762 -9.465056 90)
			(size 0.3556 1.2192)
			(layers "F.Cu" "F.Mask" "F.Paste")
			(net "GND")
		)
		(pad "B17" smd rect
			(at -1.27762 -8.865108 90)
			(size 0.3556 1.2192)
			(layers "F.Cu" "F.Mask" "F.Paste")
			(net "P5E_PEX0_STN0_TX_C_DN<0>")
		)
		(pad "B18" smd rect
			(at -1.27762 -8.264906 90)
			(size 0.3556 1.2192)
			(layers "F.Cu" "F.Mask" "F.Paste")
			(net "P5E_PEX0_STN0_TX_C_DP<0>")
		)
		(pad "B19" smd rect
			(at -1.27762 -7.664958 90)
			(size 0.3556 1.2192)
			(layers "F.Cu" "F.Mask" "F.Paste")
			(net "GND")
		)
		(pad "B20" smd rect
			(at -1.27762 -7.06501 90)
			(size 0.3556 1.2192)
			(layers "F.Cu" "F.Mask" "F.Paste")
			(net "P5E_PEX0_STN0_TX_C_DN<1>")
		)
		(pad "B21" smd rect
			(at -1.27762 -6.465062 90)
			(size 0.3556 1.2192)
			(layers "F.Cu" "F.Mask" "F.Paste")
			(net "P5E_PEX0_STN0_TX_C_DP<1>")
		)
		(pad "B22" smd rect
			(at -1.27762 -5.865114 90)
			(size 0.3556 1.2192)
			(layers "F.Cu" "F.Mask" "F.Paste")
			(net "GND")
		)
		(pad "B23" smd rect
			(at -1.27762 -5.264912 90)
			(size 0.3556 1.2192)
			(layers "F.Cu" "F.Mask" "F.Paste")
			(net "P5E_PEX0_STN0_TX_C_DN<2>")
		)
		(pad "B24" smd rect
			(at -1.27762 -4.664964 90)
			(size 0.3556 1.2192)
			(layers "F.Cu" "F.Mask" "F.Paste")
			(net "P5E_PEX0_STN0_TX_C_DP<2>")
		)
		(pad "B25" smd rect
			(at -1.27762 -4.065016 90)
			(size 0.3556 1.2192)
			(layers "F.Cu" "F.Mask" "F.Paste")
			(net "GND")
		)
		(pad "B26" smd rect
			(at -1.27762 -3.465068 90)
			(size 0.3556 1.2192)
			(layers "F.Cu" "F.Mask" "F.Paste")
			(net "P5E_PEX0_STN0_TX_C_DN<3>")
		)
		(pad "B27" smd rect
			(at -1.27762 -2.86512 90)
			(size 0.3556 1.2192)
			(layers "F.Cu" "F.Mask" "F.Paste")
			(net "P5E_PEX0_STN0_TX_C_DP<3>")
		)
		(pad "B28" smd rect
			(at -1.27762 -2.264918 90)
			(size 0.3556 1.2192)
			(layers "F.Cu" "F.Mask" "F.Paste")
			(net "GND")
		)
		(pad "B29" smd rect
			(at -1.27762 1.74498 90)
			(size 0.3556 1.2192)
			(layers "F.Cu" "F.Mask" "F.Paste")
			(net "GND")
		)
		(pad "B30" smd rect
			(at -1.27762 2.344928 90)
			(size 0.3556 1.2192)
			(layers "F.Cu" "F.Mask" "F.Paste")
			(net "P5E_PEX0_STN0_TX_C_DN<4>")
		)
		(pad "B31" smd rect
			(at -1.27762 2.944876 90)
			(size 0.3556 1.2192)
			(layers "F.Cu" "F.Mask" "F.Paste")
			(net "P5E_PEX0_STN0_TX_C_DP<4>")
		)
		(pad "B32" smd rect
			(at -1.27762 3.545078 90)
			(size 0.3556 1.2192)
			(layers "F.Cu" "F.Mask" "F.Paste")
			(net "GND")
		)
		(pad "B33" smd rect
			(at -1.27762 4.145026 90)
			(size 0.3556 1.2192)
			(layers "F.Cu" "F.Mask" "F.Paste")
			(net "P5E_PEX0_STN0_TX_C_DN<5>")
		)
		(pad "B34" smd rect
			(at -1.27762 4.744974 90)
			(size 0.3556 1.2192)
			(layers "F.Cu" "F.Mask" "F.Paste")
			(net "P5E_PEX0_STN0_TX_C_DP<5>")
		)
		(pad "B35" smd rect
			(at -1.27762 5.344922 90)
			(size 0.3556 1.2192)
			(layers "F.Cu" "F.Mask" "F.Paste")
			(net "GND")
		)
		(pad "B36" smd rect
			(at -1.27762 5.945124 90)
			(size 0.3556 1.2192)
			(layers "F.Cu" "F.Mask" "F.Paste")
			(net "P5E_PEX0_STN0_TX_C_DN<6>")
		)
		(pad "B37" smd rect
			(at -1.27762 6.545072 90)
			(size 0.3556 1.2192)
			(layers "F.Cu" "F.Mask" "F.Paste")
			(net "P5E_PEX0_STN0_TX_C_DP<6>")
		)
	)
)
